(kicad_pcb
	(version 20260206)
	(generator "pcbnew")
	(generator_version "10.0")
	(general
		(thickness 1.6)
		(legacy_teardrops no)
	)
	(paper "A4")
	(title_block
		(title "timecard-production-celestica-r4006 — R4006-B0001-02_R01.brd")
		(comment 1 "Time Appliance Project (Time Card) / footprints 236-239 of 1113")
	)
	(layers
		(0 "F.Cu" signal "TOP")
		(4 "In1.Cu" signal "L02_GND1")
		(6 "In2.Cu" signal "L03_SIG1")
		(8 "In3.Cu" signal "L04_GND2")
		(10 "In4.Cu" signal "L05_VCC1")
		(12 "In5.Cu" signal "L06_VCC2")
		(14 "In6.Cu" signal "L07_GND3")
		(16 "In7.Cu" signal "L08_SIG2")
		(18 "In8.Cu" signal "L09_GND4")
		(2 "B.Cu" signal "BOTTOM")
		(9 "F.Adhes" user "F.Adhesive")
		(11 "B.Adhes" user "B.Adhesive")
		(13 "F.Paste" user "Package Geometry/Pastemask Top")
		(15 "B.Paste" user "Package Geometry/Pastemask Bottom")
		(5 "F.SilkS" user "Ref Des/Silkscreen Top")
		(7 "B.SilkS" user "Ref Des/Silkscreen Bottom")
		(1 "F.Mask" user "Board Geometry/Soldermask Top")
		(3 "B.Mask" user "Board Geometry/Soldermask Bottom")
		(17 "Dwgs.User" user "User.Drawings")
		(19 "Cmts.User" user "User.Comments")
		(21 "Eco1.User" user "User.Eco1")
		(23 "Eco2.User" user "User.Eco2")
		(25 "Edge.Cuts" user "Board Geometry/Outline")
		(27 "Margin" user)
		(31 "F.CrtYd" user "Package Geometry/Place Bound Top")
		(29 "B.CrtYd" user "Package Geometry/Place Bound Bottom")
		(35 "F.Fab" user "Ref Des/Assembly Top")
		(33 "B.Fab" user "Ref Des/Assembly Bottom")
	)
	(footprint ""
		(layer "F.Cu")
		(at 45.02658 -16.891 180)
		(property "Reference" "U2"
			(at -0.66802 3.64363 0)
			(unlocked yes)
			(layer "F.SilkS")
			(effects
				(font
					(size 0.7874 0.5842)
					(thickness 0.1524)
				)
			)
		)
		(property "Value" ""
			(at 0 0 180)
			(layer "F.Fab")
			(effects
				(font
					(size 1.27 1.27)
				)
			)
		)
		(property "Device Type" "G220_10198_01-G223-10197-01"
			(at -0.0254 3.50647 180)
			(unlocked yes)
			(layer "F.Fab")
			(hide yes)
			(effects
				(font
					(size 0.7874 0.5842)
					(thickness 0.1524)
				)
			)
		)
		(property "User Part Number" "PARTNUM*"
			(at -0.0508 4.52247 180)
			(unlocked yes)
			(layer "Cmts.User")
			(hide yes)
			(effects
				(font
					(size 0.7874 0.5842)
					(thickness 0.1524)
				)
			)
		)
		(duplicate_pad_numbers_are_jumpers no)
		(fp_line
			(start 3.8862 2.413)
			(end 2.2098 2.413)
			(stroke
				(width 0.1)
				(type default)
			)
			(layer "F.SilkS")
		)
		(fp_line
			(start 3.8862 -2.413)
			(end 3.8862 2.413)
			(stroke
				(width 0.1)
				(type default)
			)
			(layer "F.SilkS")
		)
		(fp_line
			(start 2.2098 2.7051)
			(end -2.2098 2.7051)
			(stroke
				(width 0.1)
				(type default)
			)
			(layer "F.SilkS")
		)
		(fp_line
			(start 2.2098 2.413)
			(end 2.2098 2.7051)
			(stroke
				(width 0.1)
				(type default)
			)
			(layer "F.SilkS")
		)
		(fp_line
			(start 2.2098 -2.413)
			(end 3.8862 -2.413)
			(stroke
				(width 0.1)
				(type default)
			)
			(layer "F.SilkS")
		)
		(fp_line
			(start 2.2098 -2.7051)
			(end 2.2098 -2.413)
			(stroke
				(width 0.1)
				(type default)
			)
			(layer "F.SilkS")
		)
		(fp_line
			(start -2.2098 2.7051)
			(end -2.2098 2.413)
			(stroke
				(width 0.1)
				(type default)
			)
			(layer "F.SilkS")
		)
		(fp_line
			(start -2.2098 2.413)
			(end -3.8862 2.413)
			(stroke
				(width 0.1)
				(type default)
			)
			(layer "F.SilkS")
		)
		(fp_line
			(start -2.2098 -2.413)
			(end -2.2098 -2.7051)
			(stroke
				(width 0.1)
				(type default)
			)
			(layer "F.SilkS")
		)
		(fp_line
			(start -2.2098 -2.7051)
			(end 2.2098 -2.7051)
			(stroke
				(width 0.1)
				(type default)
			)
			(layer "F.SilkS")
		)
		(fp_line
			(start -3.8862 2.413)
			(end -3.8862 -2.413)
			(stroke
				(width 0.1)
				(type default)
			)
			(layer "F.SilkS")
		)
		(fp_line
			(start -3.8862 -2.413)
			(end -2.2098 -2.413)
			(stroke
				(width 0.1)
				(type default)
			)
			(layer "F.SilkS")
		)
		(fp_poly
			(pts
				(arc
					(start -4.892294 -1.894586)
					(mid -4.130294 -1.894586)
					(end -4.892294 -1.894586)
				)
			)
			(stroke
				(width 0)
				(type default)
			)
			(fill yes)
			(layer "F.SilkS")
		)
		(fp_rect
			(start 4.1402 -2.9591)
			(end -4.1402 2.9591)
			(stroke
				(width 0)
				(type default)
			)
			(fill no)
			(layer "F.CrtYd")
		)
		(fp_line
			(start 2.9972 2.1082)
			(end 1.9558 2.1082)
			(stroke
				(width 0.1)
				(type default)
			)
			(layer "F.Fab")
		)
		(fp_line
			(start 2.9972 1.7018)
			(end 2.9972 2.1082)
			(stroke
				(width 0.1)
				(type default)
			)
			(layer "F.Fab")
		)
		(fp_line
			(start 2.9972 0.8382)
			(end 1.9558 0.8382)
			(stroke
				(width 0.1)
				(type default)
			)
			(layer "F.Fab")
		)
		(fp_line
			(start 2.9972 0.4318)
			(end 2.9972 0.8382)
			(stroke
				(width 0.1)
				(type default)
			)
			(layer "F.Fab")
		)
		(fp_line
			(start 2.9972 -0.4318)
			(end 1.9558 -0.4318)
			(stroke
				(width 0.1)
				(type default)
			)
			(layer "F.Fab")
		)
		(fp_line
			(start 2.9972 -0.8382)
			(end 2.9972 -0.4318)
			(stroke
				(width 0.1)
				(type default)
			)
			(layer "F.Fab")
		)
		(fp_line
			(start 2.9972 -1.7018)
			(end 1.9558 -1.7018)
			(stroke
				(width 0.1)
				(type default)
			)
			(layer "F.Fab")
		)
		(fp_line
			(start 2.9972 -2.1082)
			(end 2.9972 -1.7018)
			(stroke
				(width 0.1)
				(type default)
			)
			(layer "F.Fab")
		)
		(fp_line
			(start 1.9558 2.4511)
			(end -1.9558 2.4511)
			(stroke
				(width 0.1)
				(type default)
			)
			(layer "F.Fab")
		)
		(fp_line
			(start 1.9558 1.7018)
			(end 2.9972 1.7018)
			(stroke
				(width 0.1)
				(type default)
			)
			(layer "F.Fab")
		)
		(fp_line
			(start 1.9558 0.4318)
			(end 2.9972 0.4318)
			(stroke
				(width 0.1)
				(type default)
			)
			(layer "F.Fab")
		)
		(fp_line
			(start 1.9558 -0.8382)
			(end 2.9972 -0.8382)
			(stroke
				(width 0.1)
				(type default)
			)
			(layer "F.Fab")
		)
		(fp_line
			(start 1.9558 -2.1082)
			(end 2.9972 -2.1082)
			(stroke
				(width 0.1)
				(type default)
			)
			(layer "F.Fab")
		)
		(fp_line
			(start 1.9558 -2.4511)
			(end 1.9558 2.4511)
			(stroke
				(width 0.1)
				(type default)
			)
			(layer "F.Fab")
		)
		(fp_line
			(start -1.9558 2.4511)
			(end -1.9558 -2.4511)
			(stroke
				(width 0.1)
				(type default)
			)
			(layer "F.Fab")
		)
		(fp_line
			(start -1.9558 1.7018)
			(end -2.9972 1.7018)
			(stroke
				(width 0.1)
				(type default)
			)
			(layer "F.Fab")
		)
		(fp_line
			(start -1.9558 0.4318)
			(end -2.9972 0.4318)
			(stroke
				(width 0.1)
				(type default)
			)
			(layer "F.Fab")
		)
		(fp_line
			(start -1.9558 -0.8382)
			(end -2.9972 -0.8382)
			(stroke
				(width 0.1)
				(type default)
			)
			(layer "F.Fab")
		)
		(fp_line
			(start -1.9558 -2.1082)
			(end -2.9972 -2.1082)
			(stroke
				(width 0.1)
				(type default)
			)
			(layer "F.Fab")
		)
		(fp_line
			(start -1.9558 -2.4511)
			(end 1.9558 -2.4511)
			(stroke
				(width 0.1)
				(type default)
			)
			(layer "F.Fab")
		)
		(fp_line
			(start -2.9972 2.1082)
			(end -1.9558 2.1082)
			(stroke
				(width 0.1)
				(type default)
			)
			(layer "F.Fab")
		)
		(fp_line
			(start -2.9972 1.7018)
			(end -2.9972 2.1082)
			(stroke
				(width 0.1)
				(type default)
			)
			(layer "F.Fab")
		)
		(fp_line
			(start -2.9972 0.8382)
			(end -1.9558 0.8382)
			(stroke
				(width 0.1)
				(type default)
			)
			(layer "F.Fab")
		)
		(fp_line
			(start -2.9972 0.4318)
			(end -2.9972 0.8382)
			(stroke
				(width 0.1)
				(type default)
			)
			(layer "F.Fab")
		)
		(fp_line
			(start -2.9972 -0.4318)
			(end -1.9558 -0.4318)
			(stroke
				(width 0.1)
				(type default)
			)
			(layer "F.Fab")
		)
		(fp_line
			(start -2.9972 -0.8382)
			(end -2.9972 -0.4318)
			(stroke
				(width 0.1)
				(type default)
			)
			(layer "F.Fab")
		)
		(fp_line
			(start -2.9972 -1.7018)
			(end -1.9558 -1.7018)
			(stroke
				(width 0.1)
				(type default)
			)
			(layer "F.Fab")
		)
		(fp_line
			(start -2.9972 -2.1082)
			(end -2.9972 -1.7018)
			(stroke
				(width 0.1)
				(type default)
			)
			(layer "F.Fab")
		)
		(fp_poly
			(pts
				(arc
					(start -1.284478 -1.899158)
					(mid -0.522478 -1.899158)
					(end -1.284478 -1.899158)
				)
			)
			(stroke
				(width 0)
				(type default)
			)
			(fill yes)
			(layer "F.Fab")
		)
		(fp_text user "8"
			(at 4.3688 -1.95707 0)
			(unlocked yes)
			(layer "F.SilkS")
			(effects
				(font
					(size 0.7874 0.5842)
					(thickness 0.1524)
				)
			)
		)
		(fp_text user "5"
			(at 4.25958 3.00863 0)
			(unlocked yes)
			(layer "F.SilkS")
			(effects
				(font
					(size 0.7874 0.5842)
					(thickness 0.1524)
				)
			)
		)
		(fp_text user "4"
			(at -4.37642 1.99263 0)
			(unlocked yes)
			(layer "F.SilkS")
			(effects
				(font
					(size 0.7874 0.5842)
					(thickness 0.1524)
				)
			)
		)
		(fp_text user "5"
			(at 3.8862 1.62433 0)
			(unlocked yes)
			(layer "F.Fab")
			(effects
				(font
					(size 0.7874 0.5842)
					(thickness 0.1524)
				)
			)
		)
		(fp_text user "8"
			(at 3.8608 -2.18567 0)
			(unlocked yes)
			(layer "F.Fab")
			(effects
				(font
					(size 0.7874 0.5842)
					(thickness 0.1524)
				)
			)
		)
		(fp_text user "4"
			(at -3.74142 2.00533 0)
			(unlocked yes)
			(layer "F.Fab")
			(effects
				(font
					(size 0.7874 0.5842)
					(thickness 0.1524)
				)
			)
		)
		(pad "1" smd rect
			(at -2.8067 -1.905 270)
			(size 0.508 1.651)
			(layers "F.Cu" "F.Mask" "F.Paste")
			(net "UNNAMED_3_G2201019801_I100_EN")
		)
		(pad "2" smd rect
			(at -2.8067 -0.635 270)
			(size 0.508 1.651)
			(layers "F.Cu" "F.Mask" "F.Paste")
			(net "PCIE_SMCLK")
		)
		(pad "3" smd rect
			(at -2.8067 0.635 270)
			(size 0.508 1.651)
			(layers "F.Cu" "F.Mask" "F.Paste")
			(net "PCIE_CONN_SMCLK")
		)
		(pad "4" smd rect
			(at -2.8067 1.905 270)
			(size 0.508 1.651)
			(layers "F.Cu" "F.Mask" "F.Paste")
			(net "SG")
		)
		(pad "5" smd rect
			(at 2.8067 1.905 270)
			(size 0.508 1.651)
			(layers "F.Cu" "F.Mask" "F.Paste")
			(net "Net_628")
		)
		(pad "6" smd rect
			(at 2.8067 0.635 270)
			(size 0.508 1.651)
			(layers "F.Cu" "F.Mask" "F.Paste")
			(net "PCIE_CONN_SMDAT")
		)
		(pad "7" smd rect
			(at 2.8067 -0.635 270)
			(size 0.508 1.651)
			(layers "F.Cu" "F.Mask" "F.Paste")
			(net "PCIE_SMDAT")
		)
		(pad "8" smd rect
			(at 2.8067 -1.905 270)
			(size 0.508 1.651)
			(layers "F.Cu" "F.Mask" "F.Paste")
			(net "XP3R3V_FPGA")
		)
	)
	(footprint ""
		(layer "F.Cu")
		(at 19.544792 -64.6684 -90)
		(property "Reference" "R350"
			(at 1.2954 -4.751578 90)
			(unlocked yes)
			(layer "F.SilkS")
			(effects
				(font
					(size 0.7874 0.5842)
					(thickness 0.1524)
				)
			)
		)
		(property "Value" "VAL*"
			(at 0.02032 2.13233 270)
			(unlocked yes)
			(layer "F.Fab")
			(hide yes)
			(effects
				(font
					(size 0.7874 0.5842)
					(thickness 0.1524)
				)
			)
		)
		(property "Tolerance" "TOL*"
			(at 0.044704 3.05435 270)
			(unlocked yes)
			(layer "Cmts.User")
			(hide yes)
			(effects
				(font
					(size 0.7874 0.5842)
					(thickness 0.1524)
				)
			)
		)
		(property "User Part Number" "PARTNUM*"
			(at 0.02032 4.024884 270)
			(unlocked yes)
			(layer "Cmts.User")
			(hide yes)
			(effects
				(font
					(size 0.7874 0.5842)
					(thickness 0.1524)
				)
			)
		)
		(property "Device Type" "RESISTOR-G155-100R0-J0,0OHM,-"
			(at 0.008382 1.210564 270)
			(unlocked yes)
			(layer "F.Fab")
			(hide yes)
			(effects
				(font
					(size 0.7874 0.5842)
					(thickness 0.1524)
				)
			)
		)
		(duplicate_pad_numbers_are_jumpers no)
		(fp_line
			(start -1.143 0.5588)
			(end 1.143 0.5588)
			(stroke
				(width 0.1)
				(type default)
			)
			(layer "F.SilkS")
		)
		(fp_line
			(start 1.143 0.5588)
			(end 1.143 -0.5588)
			(stroke
				(width 0.1)
				(type default)
			)
			(layer "F.SilkS")
		)
		(fp_line
			(start -1.143 -0.5588)
			(end -1.143 0.5588)
			(stroke
				(width 0.1)
				(type default)
			)
			(layer "F.SilkS")
		)
		(fp_line
			(start 1.143 -0.5588)
			(end -1.143 -0.5588)
			(stroke
				(width 0.1)
				(type default)
			)
			(layer "F.SilkS")
		)
		(fp_poly
			(pts
				(xy -1.143 0.5588) (xy 1.143 0.5588) (xy 1.143 -0.5588) (xy -1.143 -0.5588)
			)
			(stroke
				(width 0)
				(type default)
			)
			(fill no)
			(layer "F.CrtYd")
		)
		(fp_line
			(start -0.508 0.3048)
			(end 0.508 0.3048)
			(stroke
				(width 0.1)
				(type default)
			)
			(layer "F.Fab")
		)
		(fp_line
			(start 0.508 0.3048)
			(end 0.508 -0.3048)
			(stroke
				(width 0.1)
				(type default)
			)
			(layer "F.Fab")
		)
		(fp_line
			(start -0.508 -0.3048)
			(end -0.508 0.3048)
			(stroke
				(width 0.1)
				(type default)
			)
			(layer "F.Fab")
		)
		(fp_line
			(start 0.508 -0.3048)
			(end -0.508 -0.3048)
			(stroke
				(width 0.1)
				(type default)
			)
			(layer "F.Fab")
		)
		(pad "1" smd rect
			(at -0.5334 0 270)
			(size 0.7112 0.6096)
			(layers "F.Cu" "F.Mask" "F.Paste")
			(net "UNNAMED_8_ICP10100LGA10_I24_R_3")
		)
		(pad "2" smd rect
			(at 0.5334 0 270)
			(size 0.7112 0.6096)
			(layers "F.Cu" "F.Mask" "F.Paste")
			(net "XP1R8V_ICP10100")
		)
		(zone
			(layer "F.Cu")
			(hatch none 0.5)
			(connect_pads
				(clearance 0)
			)
			(min_thickness 0.25)
			(keepout
				(tracks not_allowed)
				(vias allowed)
				(pads allowed)
				(copperpour not_allowed)
				(footprints allowed)
			)
			(placement
				(enabled no)
				(sheetname "")
			)
			(fill
				(thermal_gap 0.5)
				(thermal_bridge_width 0.5)
				(island_removal_mode 0)
			)
			(polygon
				(pts
					(xy 19.239992 -64.7446) (xy 19.239992 -64.5922) (xy 19.849592 -64.5922) (xy 19.849592 -64.7446)
				)
			)
		)
		(zone
			(layer "F.Cu")
			(hatch none 0.5)
			(connect_pads
				(clearance 0)
			)
			(min_thickness 0.25)
			(keepout
				(tracks allowed)
				(vias not_allowed)
				(pads allowed)
				(copperpour not_allowed)
				(footprints allowed)
			)
			(placement
				(enabled no)
				(sheetname "")
			)
			(fill
				(thermal_gap 0.5)
				(thermal_bridge_width 0.5)
				(island_removal_mode 0)
			)
			(polygon
				(pts
					(xy 19.239992 -64.7446) (xy 19.239992 -64.5922) (xy 19.849592 -64.5922) (xy 19.849592 -64.7446)
				)
			)
		)
	)
	(footprint ""
		(layer "F.Cu")
		(at 146.304 -62.611)
		(property "Reference" "TP39"
			(at -1.7272 -1.35763 0)
			(unlocked yes)
			(layer "F.SilkS")
			(effects
				(font
					(size 0.7874 0.5842)
					(thickness 0.1524)
				)
				(justify left)
			)
		)
		(property "Value" ""
			(at 0 0 0)
			(layer "F.Fab")
			(effects
				(font
					(size 1.27 1.27)
				)
			)
		)
		(property "Device Type" "TP_PIONT-TP010CT020B030_PTH-TPA"
			(at -1.341882 0.996696 0)
			(unlocked yes)
			(layer "F.Fab")
			(hide yes)
			(effects
				(font
					(size 0.7874 0.5842)
					(thickness 0.000001)
				)
				(justify left)
			)
		)
		(duplicate_pad_numbers_are_jumpers no)
		(fp_poly
			(pts
				(arc
					(start 0.889 0)
					(mid -0.889 0)
					(end 0.889 0)
				)
			)
			(stroke
				(width 0)
				(type default)
			)
			(fill no)
			(layer "B.CrtYd")
		)
		(fp_poly
			(pts
				(arc
					(start 0.889 0)
					(mid -0.889 0)
					(end 0.889 0)
				)
			)
			(stroke
				(width 0)
				(type default)
			)
			(fill no)
			(layer "F.CrtYd")
		)
		(pad "1" thru_hole circle
			(at 0 0)
			(size 0.508 0.508)
			(drill 0.254)
			(layers "*.Cu" "*.Mask")
			(remove_unused_layers no)
			(net "XP1R0V_FPGA_PG")
			(clearance 0.1016)
			(padstack
				(mode front_inner_back)
				(layer "Inner"
					(shape circle)
					(size 0.508 0.508)
					(clearance 0.1016)
				)
				(layer "B.Cu"
					(shape circle)
					(size 0.762 0.762)
					(clearance -0.0254)
				)
			)
		)
	)
	(footprint ""
		(layer "F.Cu")
		(at 126.619 -89.535 90)
		(property "Reference" "R112"
			(at -3.429 0.54737 90)
			(unlocked yes)
			(layer "F.SilkS")
			(effects
				(font
					(size 0.7874 0.5842)
					(thickness 0.1524)
				)
			)
		)
		(property "Value" "VAL*"
			(at 0.02032 2.13233 90)
			(unlocked yes)
			(layer "F.Fab")
			(hide yes)
			(effects
				(font
					(size 0.7874 0.5842)
					(thickness 0.1524)
				)
			)
		)
		(property "Tolerance" "TOL*"
			(at 0.044704 3.05435 90)
			(unlocked yes)
			(layer "Cmts.User")
			(hide yes)
			(effects
				(font
					(size 0.7874 0.5842)
					(thickness 0.1524)
				)
			)
		)
		(property "User Part Number" "PARTNUM*"
			(at 0.02032 4.024884 90)
			(unlocked yes)
			(layer "Cmts.User")
			(hide yes)
			(effects
				(font
					(size 0.7874 0.5842)
					(thickness 0.1524)
				)
			)
		)
		(property "Device Type" "RESISTOR-G155-133R0-01,33OHM,1%"
			(at 0.008382 1.210564 90)
			(unlocked yes)
			(layer "F.Fab")
			(hide yes)
			(effects
				(font
					(size 0.7874 0.5842)
					(thickness 0.1524)
				)
			)
		)
		(duplicate_pad_numbers_are_jumpers no)
		(fp_line
			(start 1.143 -0.5588)
			(end -1.143 -0.5588)
			(stroke
				(width 0.1)
				(type default)
			)
			(layer "F.SilkS")
		)
		(fp_line
			(start -1.143 -0.5588)
			(end -1.143 0.5588)
			(stroke
				(width 0.1)
				(type default)
			)
			(layer "F.SilkS")
		)
		(fp_line
			(start 1.143 0.5588)
			(end 1.143 -0.5588)
			(stroke
				(width 0.1)
				(type default)
			)
			(layer "F.SilkS")
		)
		(fp_line
			(start -1.143 0.5588)
			(end 1.143 0.5588)
			(stroke
				(width 0.1)
				(type default)
			)
			(layer "F.SilkS")
		)
		(fp_rect
			(start -1.143 0.5588)
			(end 1.143 -0.5588)
			(stroke
				(width 0)
				(type default)
			)
			(fill no)
			(layer "F.CrtYd")
		)
		(fp_line
			(start 0.508 -0.3048)
			(end -0.508 -0.3048)
			(stroke
				(width 0.1)
				(type default)
			)
			(layer "F.Fab")
		)
		(fp_line
			(start -0.508 -0.3048)
			(end -0.508 0.3048)
			(stroke
				(width 0.1)
				(type default)
			)
			(layer "F.Fab")
		)
		(fp_line
			(start 0.508 0.3048)
			(end 0.508 -0.3048)
			(stroke
				(width 0.1)
				(type default)
			)
			(layer "F.Fab")
		)
		(fp_line
			(start -0.508 0.3048)
			(end 0.508 0.3048)
			(stroke
				(width 0.1)
				(type default)
			)
			(layer "F.Fab")
		)
		(pad "1" smd rect
			(at -0.5334 0 90)
			(size 0.7112 0.6096)
			(layers "F.Cu" "F.Mask" "F.Paste")
			(net "DBG_UART_GPS_TXD")
		)
		(pad "2" smd rect
			(at 0.5334 0 90)
			(size 0.7112 0.6096)
			(layers "F.Cu" "F.Mask" "F.Paste")
			(net "GPS_UART_TXD")
		)
		(zone
			(layer "F.Cu")
			(hatch none 0.5)
			(connect_pads
				(clearance 0)
			)
			(min_thickness 0.25)
			(keepout
				(tracks allowed)
				(vias not_allowed)
				(pads allowed)
				(copperpour not_allowed)
				(footprints allowed)
			)
			(placement
				(enabled no)
				(sheetname "")
			)
			(fill
				(thermal_gap 0.5)
				(thermal_bridge_width 0.5)
				(island_removal_mode 0)
			)
			(polygon
				(pts
					(xy 126.9238 -89.4588) (xy 126.9238 -89.6112) (xy 126.3142 -89.6112) (xy 126.3142 -89.4588)
				)
			)
		)
	)
)
